FILE_TYPE = CONNECTIVITY;
{Allegro Design Entry HDL 17.2-2016 S081 (4005846) 1/11/2022}
"PAGE_NUMBER" = 68;
0"NC";
1"GND\g";
2"GND\g";
3"PVDDCR_CPU0_P0\g";
4"PVDDCR_CPU0_P0\g";
5"PVDDCR_CPU0_P0\g";
6"GND\g";
7"PVDDCR_CPU0_P0\g";
8"GND\g";
9"GND\g";
10"PVDDCR_CPU0_P0\g";
11"PVDDCR_CPU1_P0\g";
12"GND\g";
13"PVDDCR_CPU1_P0\g";
14"GND\g";
15"PVDDCR_CPU1_P0\g";
16"GND\g";
17"PVDDCR_CPU1_P0\g";
18"GND\g";
19"PVDDCR_CPU1_P0\g";
20"GND\g";
%"Q_CAP"
"1","(-9000,2075)","0","pure_quanta","I1";
;
LOCATION"C2167"
$SEC"1"
CDS_SEC"1"
MATERIAL"X6S"
TOLERANCE"20%"
VALUE"22UF"
PART_NUMBER"CH622KMEB02"
VOLTAGE"4V"
PACK_TYPE"C0402"
CDS_LIB"pure_quanta";
"B"
$PN"2"1;
"A"
$PN"1"3;
%"Q_CAP"
"1","(-9000,4475)","0","pure_quanta","I10";
;
LOCATION"C246"
$SEC"1"
CDS_SEC"1"
MATERIAL"X6S"
TOLERANCE"20%"
VALUE"22UF"
PART_NUMBER"CH622KMEB02"
VOLTAGE"4V"
PACK_TYPE"C0402"
CDS_LIB"pure_quanta";
"B"
$PN"2"8;
"A"
$PN"1"7;
%"Q_CAP"
"1","(-2175,5250)","0","pure_quanta","I100";
;
LOCATION"C2231"
$SEC"1"
CDS_SEC"1"
MATERIAL"X6S"
TOLERANCE"20%"
VALUE"22UF"
PART_NUMBER"CH622KMEB02"
VOLTAGE"4V"
PACK_TYPE"C0402"
CDS_LIB"pure_quanta";
"B"
$PN"2"12;
"A"
$PN"1"11;
%"Q_CAP"
"1","(-1725,4475)","0","pure_quanta","I101";
;
LOCATION"C2238"
$SEC"1"
CDS_SEC"1"
MATERIAL"X6S"
TOLERANCE"20%"
VALUE"22UF"
PART_NUMBER"CH622KMEB02"
VOLTAGE"4V"
PACK_TYPE"C0402"
CDS_LIB"pure_quanta";
"B"
$PN"2"14;
"A"
$PN"1"13;
%"Q_CAP"
"1","(-1275,4475)","0","pure_quanta","I102";
;
LOCATION"C2244"
$SEC"1"
CDS_SEC"1"
MATERIAL"X6S"
TOLERANCE"20%"
VALUE"22UF"
PART_NUMBER"CH622KMEB02"
VOLTAGE"4V"
PACK_TYPE"C0402"
CDS_LIB"pure_quanta";
"B"
$PN"2"14;
"A"
$PN"1"13;
%"Q_CAP"
"1","(-1725,5250)","0","pure_quanta","I103";
;
LOCATION"C2237"
$SEC"1"
CDS_SEC"1"
MATERIAL"X6S"
TOLERANCE"20%"
VALUE"22UF"
PART_NUMBER"CH622KMEB02"
VOLTAGE"4V"
PACK_TYPE"C0402"
CDS_LIB"pure_quanta";
"B"
$PN"2"12;
"A"
$PN"1"11;
%"Q_CAP"
"1","(-1275,5250)","0","pure_quanta","I104";
;
LOCATION"C2243"
$SEC"1"
CDS_SEC"1"
MATERIAL"X6S"
TOLERANCE"20%"
VALUE"22UF"
PART_NUMBER"CH622KMEB02"
VOLTAGE"4V"
PACK_TYPE"C0402"
CDS_LIB"pure_quanta";
"B"
$PN"2"12;
"A"
$PN"1"11;
%"Q_CAP"
"1","(-825,4475)","0","pure_quanta","I105";
;
LOCATION"C2249"
$SEC"1"
CDS_SEC"1"
MATERIAL"X6S"
TOLERANCE"20%"
VALUE"22UF"
PART_NUMBER"CH622KMEB02"
VOLTAGE"4V"
PACK_TYPE"C0402"
CDS_LIB"pure_quanta";
"B"
$PN"2"14;
"A"
$PN"1"13;
%"Q_CAP"
"1","(-425,4475)","0","pure_quanta","I106";
;
LOCATION"C2254"
$SEC"1"
CDS_SEC"1"
MATERIAL"X6S"
TOLERANCE"20%"
VALUE"22UF"
PART_NUMBER"CH622KMEB02"
VOLTAGE"4V"
PACK_TYPE"C0402"
CDS_LIB"pure_quanta";
"B"
$PN"2"14;
"A"
$PN"1"13;
%"UNIVERSAL_GND"
"1","(-425,4875)","0","pure_quanta_power","I107";
;
CDS_LIB"pure_quanta_power"
HDL_POWER"GND";
"A"12;
%"Q_CAP"
"1","(-825,5250)","0","pure_quanta","I108";
;
LOCATION"C2248"
$SEC"1"
CDS_SEC"1"
MATERIAL"X6S"
TOLERANCE"20%"
VALUE"22UF"
PART_NUMBER"CH622KMEB02"
VOLTAGE"4V"
PACK_TYPE"C0402"
CDS_LIB"pure_quanta";
"B"
$PN"2"12;
"A"
$PN"1"11;
%"Q_CAP"
"1","(-425,5250)","0","pure_quanta","I109";
;
LOCATION"C2253"
$SEC"1"
CDS_SEC"1"
MATERIAL"X6S"
TOLERANCE"20%"
VALUE"22UF"
PART_NUMBER"CH622KMEB02"
VOLTAGE"4V"
PACK_TYPE"C0402"
CDS_LIB"pure_quanta";
"B"
$PN"2"12;
"A"
$PN"1"11;
%"UNIVERSAL_POWER"
"1","(-9000,4750)","0","pure_quanta_power","I11";
;
HDL_POWER"PVDDCR_CPU0_P0"
CDS_LIB"pure_quanta_power";
"A"7;
%"Q_CAP"
"1","(-6300,5250)","0","pure_quanta","I110";
;
LOCATION"C272"
$SEC"1"
CDS_SEC"1"
MATERIAL"X6S"
TOLERANCE"20%"
VALUE"22UF"
PART_NUMBER"CH622KMEB02"
VOLTAGE"4V"
PACK_TYPE"C0402"
CDS_LIB"pure_quanta";
"B"
$PN"2"9;
"A"
$PN"1"10;
%"Q_CAP"
"1","(-8550,4475)","0","pure_quanta","I12";
;
LOCATION"C252"
$SEC"1"
CDS_SEC"1"
MATERIAL"X6S"
TOLERANCE"20%"
VALUE"22UF"
PART_NUMBER"CH622KMEB02"
VOLTAGE"4V"
PACK_TYPE"C0402"
CDS_LIB"pure_quanta";
"B"
$PN"2"8;
"A"
$PN"1"7;
%"UNIVERSAL_POWER"
"1","(-9000,5525)","0","pure_quanta_power","I13";
;
HDL_POWER"PVDDCR_CPU0_P0"
CDS_LIB"pure_quanta_power";
"A"10;
%"Q_CAP"
"1","(-9000,5250)","0","pure_quanta","I14";
;
LOCATION"C245"
$SEC"1"
CDS_SEC"1"
MATERIAL"X6S"
TOLERANCE"20%"
VALUE"22UF"
PART_NUMBER"CH622KMEB02"
VOLTAGE"4V"
PACK_TYPE"C0402"
CDS_LIB"pure_quanta";
"B"
$PN"2"9;
"A"
$PN"1"10;
%"Q_CAP"
"1","(-8550,5250)","0","pure_quanta","I15";
;
LOCATION"C251"
$SEC"1"
CDS_SEC"1"
MATERIAL"X6S"
TOLERANCE"20%"
VALUE"22UF"
PART_NUMBER"CH622KMEB02"
VOLTAGE"4V"
PACK_TYPE"C0402"
CDS_LIB"pure_quanta";
"B"
$PN"2"9;
"A"
$PN"1"10;
%"Q_CAP"
"1","(-8100,2075)","0","pure_quanta","I16";
;
LOCATION"C2175"
$SEC"1"
CDS_SEC"1"
MATERIAL"X6S"
TOLERANCE"20%"
VALUE"22UF"
PART_NUMBER"CH622KMEB02"
VOLTAGE"4V"
PACK_TYPE"C0402"
CDS_LIB"pure_quanta";
"B"
$PN"2"1;
"A"
$PN"1"3;
%"Q_CAP"
"1","(-7650,2075)","0","pure_quanta","I17";
;
LOCATION"C2179"
$SEC"1"
CDS_SEC"1"
MATERIAL"X6S"
TOLERANCE"20%"
VALUE"22UF"
PART_NUMBER"CH622KMEB02"
VOLTAGE"4V"
PACK_TYPE"C0402"
CDS_LIB"pure_quanta";
"B"
$PN"2"1;
"A"
$PN"1"3;
%"UNIVERSAL_GND"
"1","(-7200,1675)","0","pure_quanta_power","I18";
;
CDS_LIB"pure_quanta_power"
HDL_POWER"GND";
"A"1;
%"Q_CAP"
"1","(-7200,2075)","0","pure_quanta","I19";
;
LOCATION"C2183"
$SEC"1"
CDS_SEC"1"
MATERIAL"X6S"
TOLERANCE"20%"
VALUE"22UF"
PART_NUMBER"CH622KMEB02"
VOLTAGE"4V"
PACK_TYPE"C0402"
CDS_LIB"pure_quanta";
"B"
$PN"2"1;
"A"
$PN"1"3;
%"Q_CAP"
"1","(-8550,2075)","0","pure_quanta","I2";
;
LOCATION"C2171"
$SEC"1"
CDS_SEC"1"
MATERIAL"X6S"
TOLERANCE"20%"
VALUE"22UF"
PART_NUMBER"CH622KMEB02"
VOLTAGE"4V"
PACK_TYPE"C0402"
CDS_LIB"pure_quanta";
"B"
$PN"2"1;
"A"
$PN"1"3;
%"Q_CAP"
"1","(-8100,2875)","0","pure_quanta","I20";
;
LOCATION"C2174"
$SEC"1"
CDS_SEC"1"
MATERIAL"X6S"
TOLERANCE"20%"
VALUE"22UF"
PART_NUMBER"CH622KMEB02"
VOLTAGE"4V"
PACK_TYPE"C0402"
CDS_LIB"pure_quanta";
"B"
$PN"2"2;
"A"
$PN"1"4;
%"Q_CAP"
"1","(-7650,2875)","0","pure_quanta","I21";
;
LOCATION"C2178"
$SEC"1"
CDS_SEC"1"
MATERIAL"X6S"
TOLERANCE"20%"
VALUE"22UF"
PART_NUMBER"CH622KMEB02"
VOLTAGE"4V"
PACK_TYPE"C0402"
CDS_LIB"pure_quanta";
"B"
$PN"2"2;
"A"
$PN"1"4;
%"Q_CAP"
"1","(-8100,3675)","0","pure_quanta","I22";
;
LOCATION"C2173"
$SEC"1"
CDS_SEC"1"
MATERIAL"X6S"
TOLERANCE"20%"
VALUE"22UF"
PART_NUMBER"CH622KMEB02"
VOLTAGE"4V"
PACK_TYPE"C0402"
CDS_LIB"pure_quanta";
"B"
$PN"2"6;
"A"
$PN"1"5;
%"Q_CAP"
"1","(-7650,3675)","0","pure_quanta","I23";
;
LOCATION"C2177"
$SEC"1"
CDS_SEC"1"
MATERIAL"X6S"
TOLERANCE"20%"
VALUE"22UF"
PART_NUMBER"CH622KMEB02"
VOLTAGE"4V"
PACK_TYPE"C0402"
CDS_LIB"pure_quanta";
"B"
$PN"2"6;
"A"
$PN"1"5;
%"Q_CAP"
"1","(-7200,2875)","0","pure_quanta","I24";
;
LOCATION"C2182"
$SEC"1"
CDS_SEC"1"
MATERIAL"X6S"
TOLERANCE"20%"
VALUE"22UF"
PART_NUMBER"CH622KMEB02"
VOLTAGE"4V"
PACK_TYPE"C0402"
CDS_LIB"pure_quanta";
"B"
$PN"2"2;
"A"
$PN"1"4;
%"Q_CAP"
"1","(-7200,3675)","0","pure_quanta","I25";
;
LOCATION"C2181"
$SEC"1"
CDS_SEC"1"
MATERIAL"X6S"
TOLERANCE"20%"
VALUE"22UF"
PART_NUMBER"CH622KMEB02"
VOLTAGE"4V"
PACK_TYPE"C0402"
CDS_LIB"pure_quanta";
"B"
$PN"2"6;
"A"
$PN"1"5;
%"Q_CAP"
"1","(-6750,2875)","0","pure_quanta","I26";
;
LOCATION"C2186"
$SEC"1"
CDS_SEC"1"
MATERIAL"X6S"
TOLERANCE"20%"
VALUE"22UF"
PART_NUMBER"CH622KMEB02"
VOLTAGE"4V"
PACK_TYPE"C0402"
CDS_LIB"pure_quanta";
"B"
$PN"2"2;
"A"
$PN"1"4;
%"Q_CAP"
"1","(-6300,2875)","0","pure_quanta","I27";
;
LOCATION"C2190"
$SEC"1"
CDS_SEC"1"
MATERIAL"X6S"
TOLERANCE"20%"
VALUE"22UF"
PART_NUMBER"CH622KMEB02"
VOLTAGE"4V"
PACK_TYPE"C0402"
CDS_LIB"pure_quanta";
"B"
$PN"2"2;
"A"
$PN"1"4;
%"Q_CAP"
"1","(-6750,3675)","0","pure_quanta","I28";
;
LOCATION"C2185"
$SEC"1"
CDS_SEC"1"
MATERIAL"X6S"
TOLERANCE"20%"
VALUE"22UF"
PART_NUMBER"CH622KMEB02"
VOLTAGE"4V"
PACK_TYPE"C0402"
CDS_LIB"pure_quanta";
"B"
$PN"2"6;
"A"
$PN"1"5;
%"Q_CAP"
"1","(-6300,3675)","0","pure_quanta","I29";
;
LOCATION"C2189"
$SEC"1"
CDS_SEC"1"
MATERIAL"X6S"
TOLERANCE"20%"
VALUE"22UF"
PART_NUMBER"CH622KMEB02"
VOLTAGE"4V"
PACK_TYPE"C0402"
CDS_LIB"pure_quanta";
"B"
$PN"2"6;
"A"
$PN"1"5;
%"UNIVERSAL_POWER"
"1","(-9000,2350)","0","pure_quanta_power","I3";
;
HDL_POWER"PVDDCR_CPU0_P0"
CDS_LIB"pure_quanta_power";
"A"3;
%"Q_CAP"
"1","(-4425,2075)","0","pure_quanta","I30";
;
LOCATION"C2205"
$SEC"1"
CDS_SEC"1"
MATERIAL"X6S"
TOLERANCE"20%"
VALUE"22UF"
PART_NUMBER"CH622KMEB02"
VOLTAGE"4V"
PACK_TYPE"C0402"
CDS_LIB"pure_quanta";
"B"
$PN"2"20;
"A"
$PN"1"19;
%"Q_CAP"
"1","(-5850,2875)","0","pure_quanta","I31";
;
LOCATION"C2193"
$SEC"1"
CDS_SEC"1"
MATERIAL"X6S"
TOLERANCE"20%"
VALUE"22UF"
PART_NUMBER"CH622KMEB02"
VOLTAGE"4V"
PACK_TYPE"C0402"
CDS_LIB"pure_quanta";
"B"
$PN"2"2;
"A"
$PN"1"4;
%"Q_CAP"
"1","(-5400,2875)","0","pure_quanta","I32";
;
LOCATION"C2196"
$SEC"1"
CDS_SEC"1"
MATERIAL"X6S"
TOLERANCE"20%"
VALUE"22UF"
PART_NUMBER"CH622KMEB02"
VOLTAGE"4V"
PACK_TYPE"C0402"
CDS_LIB"pure_quanta";
"B"
$PN"2"2;
"A"
$PN"1"4;
%"Q_CAP"
"1","(-5850,3675)","0","pure_quanta","I33";
;
LOCATION"C2192"
$SEC"1"
CDS_SEC"1"
MATERIAL"X6S"
TOLERANCE"20%"
VALUE"22UF"
PART_NUMBER"CH622KMEB02"
VOLTAGE"4V"
PACK_TYPE"C0402"
CDS_LIB"pure_quanta";
"B"
$PN"2"6;
"A"
$PN"1"5;
%"Q_CAP"
"1","(-5400,3675)","0","pure_quanta","I34";
;
LOCATION"C2195"
$SEC"1"
CDS_SEC"1"
MATERIAL"X6S"
TOLERANCE"20%"
VALUE"22UF"
PART_NUMBER"CH622KMEB02"
VOLTAGE"4V"
PACK_TYPE"C0402"
CDS_LIB"pure_quanta";
"B"
$PN"2"6;
"A"
$PN"1"5;
%"UNIVERSAL_GND"
"1","(-5000,2500)","0","pure_quanta_power","I35";
;
CDS_LIB"pure_quanta_power"
HDL_POWER"GND";
"A"2;
%"Q_CAP"
"1","(-5000,2875)","0","pure_quanta","I36";
;
LOCATION"C2199"
$SEC"1"
CDS_SEC"1"
MATERIAL"X6S"
TOLERANCE"20%"
VALUE"22UF"
PART_NUMBER"CH622KMEB02"
VOLTAGE"4V"
PACK_TYPE"C0402"
CDS_LIB"pure_quanta";
"B"
$PN"2"2;
"A"
$PN"1"4;
%"UNIVERSAL_POWER"
"1","(-4425,2350)","0","pure_quanta_power","I37";
;
HDL_POWER"PVDDCR_CPU1_P0"
CDS_LIB"pure_quanta_power";
"A"19;
%"Q_CAP"
"1","(-4425,2875)","0","pure_quanta","I38";
;
LOCATION"C2204"
$SEC"1"
CDS_SEC"1"
MATERIAL"X6S"
TOLERANCE"20%"
VALUE"22UF"
PART_NUMBER"CH622KMEB02"
VOLTAGE"4V"
PACK_TYPE"C0402"
CDS_LIB"pure_quanta";
"B"
$PN"2"18;
"A"
$PN"1"17;
%"UNIVERSAL_GND"
"1","(-5000,3300)","0","pure_quanta_power","I39";
;
CDS_LIB"pure_quanta_power"
HDL_POWER"GND";
"A"6;
%"Q_CAP"
"1","(-9000,2875)","0","pure_quanta","I4";
;
LOCATION"C2166"
$SEC"1"
CDS_SEC"1"
MATERIAL"X6S"
TOLERANCE"20%"
VALUE"22UF"
PART_NUMBER"CH622KMEB02"
VOLTAGE"4V"
PACK_TYPE"C0402"
CDS_LIB"pure_quanta";
"B"
$PN"2"2;
"A"
$PN"1"4;
%"Q_CAP"
"1","(-5000,3675)","0","pure_quanta","I40";
;
LOCATION"C2198"
$SEC"1"
CDS_SEC"1"
MATERIAL"X6S"
TOLERANCE"20%"
VALUE"22UF"
PART_NUMBER"CH622KMEB02"
VOLTAGE"4V"
PACK_TYPE"C0402"
CDS_LIB"pure_quanta";
"B"
$PN"2"6;
"A"
$PN"1"5;
%"UNIVERSAL_GND"
"1","(-5000,4100)","0","pure_quanta_power","I41";
;
CDS_LIB"pure_quanta_power"
HDL_POWER"GND";
"A"8;
%"UNIVERSAL_POWER"
"1","(-4425,3150)","0","pure_quanta_power","I42";
;
HDL_POWER"PVDDCR_CPU1_P0"
CDS_LIB"pure_quanta_power";
"A"17;
%"Q_CAP"
"1","(-4425,3675)","0","pure_quanta","I43";
;
LOCATION"C2203"
$SEC"1"
CDS_SEC"1"
MATERIAL"X6S"
TOLERANCE"20%"
VALUE"22UF"
PART_NUMBER"CH622KMEB02"
VOLTAGE"4V"
PACK_TYPE"C0402"
CDS_LIB"pure_quanta";
"B"
$PN"2"16;
"A"
$PN"1"15;
%"UNIVERSAL_POWER"
"1","(-4425,3950)","0","pure_quanta_power","I44";
;
HDL_POWER"PVDDCR_CPU1_P0"
CDS_LIB"pure_quanta_power";
"A"15;
%"Q_CAP"
"1","(-8100,4475)","0","pure_quanta","I45";
;
LOCATION"C1922"
$SEC"1"
CDS_SEC"1"
MATERIAL"X6S"
TOLERANCE"20%"
VALUE"22UF"
PART_NUMBER"CH622KMEB02"
VOLTAGE"4V"
PACK_TYPE"C0402"
CDS_LIB"pure_quanta";
"B"
$PN"2"8;
"A"
$PN"1"7;
%"Q_CAP"
"1","(-7650,4475)","0","pure_quanta","I46";
;
LOCATION"C263"
$SEC"1"
CDS_SEC"1"
MATERIAL"X6S"
TOLERANCE"20%"
VALUE"22UF"
PART_NUMBER"CH622KMEB02"
VOLTAGE"4V"
PACK_TYPE"C0402"
CDS_LIB"pure_quanta";
"B"
$PN"2"8;
"A"
$PN"1"7;
%"Q_CAP"
"1","(-8100,5250)","0","pure_quanta","I47";
;
LOCATION"C4178"
$SEC"1"
CDS_SEC"1"
MATERIAL"X6S"
TOLERANCE"20%"
VALUE"22UF"
PART_NUMBER"CH622KMEB02"
VOLTAGE"4V"
PACK_TYPE"C0402"
CDS_LIB"pure_quanta";
"B"
$PN"2"9;
"A"
$PN"1"10;
%"Q_CAP"
"1","(-7650,5250)","0","pure_quanta","I48";
;
LOCATION"C4179"
$SEC"1"
CDS_SEC"1"
MATERIAL"X6S"
TOLERANCE"20%"
VALUE"22UF"
PART_NUMBER"CH622KMEB02"
VOLTAGE"4V"
PACK_TYPE"C0402"
CDS_LIB"pure_quanta";
"B"
$PN"2"9;
"A"
$PN"1"10;
%"Q_CAP"
"1","(-7200,4475)","0","pure_quanta","I49";
;
LOCATION"C268"
$SEC"1"
CDS_SEC"1"
MATERIAL"X6S"
TOLERANCE"20%"
VALUE"22UF"
PART_NUMBER"CH622KMEB02"
VOLTAGE"4V"
PACK_TYPE"C0402"
CDS_LIB"pure_quanta";
"B"
$PN"2"8;
"A"
$PN"1"7;
%"Q_CAP"
"1","(-8550,2875)","0","pure_quanta","I5";
;
LOCATION"C2170"
$SEC"1"
CDS_SEC"1"
MATERIAL"X6S"
TOLERANCE"20%"
VALUE"22UF"
PART_NUMBER"CH622KMEB02"
VOLTAGE"4V"
PACK_TYPE"C0402"
CDS_LIB"pure_quanta";
"B"
$PN"2"2;
"A"
$PN"1"4;
%"Q_CAP"
"1","(-7200,5250)","0","pure_quanta","I50";
;
LOCATION"C267"
$SEC"1"
CDS_SEC"1"
MATERIAL"X6S"
TOLERANCE"20%"
VALUE"22UF"
PART_NUMBER"CH622KMEB02"
VOLTAGE"4V"
PACK_TYPE"C0402"
CDS_LIB"pure_quanta";
"B"
$PN"2"9;
"A"
$PN"1"10;
%"Q_CAP"
"1","(-6750,4475)","0","pure_quanta","I51";
;
LOCATION"C271"
$SEC"1"
CDS_SEC"1"
MATERIAL"X6S"
TOLERANCE"20%"
VALUE"22UF"
PART_NUMBER"CH622KMEB02"
VOLTAGE"4V"
PACK_TYPE"C0402"
CDS_LIB"pure_quanta";
"B"
$PN"2"8;
"A"
$PN"1"7;
%"Q_CAP"
"1","(-6300,4475)","0","pure_quanta","I52";
;
LOCATION"C273"
$SEC"1"
CDS_SEC"1"
MATERIAL"X6S"
TOLERANCE"20%"
VALUE"22UF"
PART_NUMBER"CH622KMEB02"
VOLTAGE"4V"
PACK_TYPE"C0402"
CDS_LIB"pure_quanta";
"B"
$PN"2"8;
"A"
$PN"1"7;
%"Q_CAP"
"1","(-6750,5250)","0","pure_quanta","I53";
;
LOCATION"C270"
$SEC"1"
CDS_SEC"1"
MATERIAL"X6S"
TOLERANCE"20%"
VALUE"22UF"
PART_NUMBER"CH622KMEB02"
VOLTAGE"4V"
PACK_TYPE"C0402"
CDS_LIB"pure_quanta";
"B"
$PN"2"9;
"A"
$PN"1"10;
%"Q_CAP"
"1","(-5850,4475)","0","pure_quanta","I54";
;
LOCATION"C275"
$SEC"1"
CDS_SEC"1"
MATERIAL"X6S"
TOLERANCE"20%"
VALUE"22UF"
PART_NUMBER"CH622KMEB02"
VOLTAGE"4V"
PACK_TYPE"C0402"
CDS_LIB"pure_quanta";
"B"
$PN"2"8;
"A"
$PN"1"7;
%"Q_CAP"
"1","(-5400,4475)","0","pure_quanta","I55";
;
LOCATION"C277"
$SEC"1"
CDS_SEC"1"
MATERIAL"X6S"
TOLERANCE"20%"
VALUE"22UF"
PART_NUMBER"CH622KMEB02"
VOLTAGE"4V"
PACK_TYPE"C0402"
CDS_LIB"pure_quanta";
"B"
$PN"2"8;
"A"
$PN"1"7;
%"Q_CAP"
"1","(-5850,5250)","0","pure_quanta","I56";
;
LOCATION"C274"
$SEC"1"
CDS_SEC"1"
MATERIAL"X6S"
TOLERANCE"20%"
VALUE"22UF"
PART_NUMBER"CH622KMEB02"
VOLTAGE"4V"
PACK_TYPE"C0402"
CDS_LIB"pure_quanta";
"B"
$PN"2"9;
"A"
$PN"1"10;
%"Q_CAP"
"1","(-5400,5250)","0","pure_quanta","I57";
;
LOCATION"C276"
$SEC"1"
CDS_SEC"1"
MATERIAL"X6S"
TOLERANCE"20%"
VALUE"22UF"
PART_NUMBER"CH622KMEB02"
VOLTAGE"4V"
PACK_TYPE"C0402"
CDS_LIB"pure_quanta";
"B"
$PN"2"9;
"A"
$PN"1"10;
%"Q_CAP"
"1","(-5000,4475)","0","pure_quanta","I58";
;
LOCATION"C279"
$SEC"1"
CDS_SEC"1"
MATERIAL"X6S"
TOLERANCE"20%"
VALUE"22UF"
PART_NUMBER"CH622KMEB02"
VOLTAGE"4V"
PACK_TYPE"C0402"
CDS_LIB"pure_quanta";
"B"
$PN"2"8;
"A"
$PN"1"7;
%"UNIVERSAL_GND"
"1","(-5000,4875)","0","pure_quanta_power","I59";
;
CDS_LIB"pure_quanta_power"
HDL_POWER"GND";
"A"9;
%"UNIVERSAL_POWER"
"1","(-9000,3150)","0","pure_quanta_power","I6";
;
HDL_POWER"PVDDCR_CPU0_P0"
CDS_LIB"pure_quanta_power";
"A"4;
%"Q_CAP"
"1","(-4425,4475)","0","pure_quanta","I60";
;
LOCATION"C2202"
$SEC"1"
CDS_SEC"1"
MATERIAL"X6S"
TOLERANCE"20%"
VALUE"22UF"
PART_NUMBER"CH622KMEB02"
VOLTAGE"4V"
PACK_TYPE"C0402"
CDS_LIB"pure_quanta";
"B"
$PN"2"14;
"A"
$PN"1"13;
%"UNIVERSAL_POWER"
"1","(-4425,4750)","0","pure_quanta_power","I61";
;
HDL_POWER"PVDDCR_CPU1_P0"
CDS_LIB"pure_quanta_power";
"A"13;
%"Q_CAP"
"1","(-5000,5250)","0","pure_quanta","I62";
;
LOCATION"C278"
$SEC"1"
CDS_SEC"1"
MATERIAL"X6S"
TOLERANCE"20%"
VALUE"22UF"
PART_NUMBER"CH622KMEB02"
VOLTAGE"4V"
PACK_TYPE"C0402"
CDS_LIB"pure_quanta";
"B"
$PN"2"9;
"A"
$PN"1"10;
%"Q_CAP"
"1","(-4425,5250)","0","pure_quanta","I63";
;
LOCATION"C2201"
$SEC"1"
CDS_SEC"1"
MATERIAL"X6S"
TOLERANCE"20%"
VALUE"22UF"
PART_NUMBER"CH622KMEB02"
VOLTAGE"4V"
PACK_TYPE"C0402"
CDS_LIB"pure_quanta";
"B"
$PN"2"12;
"A"
$PN"1"11;
%"UNIVERSAL_POWER"
"1","(-4425,5525)","0","pure_quanta_power","I64";
;
HDL_POWER"PVDDCR_CPU1_P0"
CDS_LIB"pure_quanta_power";
"A"11;
%"Q_CAP"
"1","(-3975,2075)","0","pure_quanta","I65";
;
LOCATION"C2211"
$SEC"1"
CDS_SEC"1"
MATERIAL"X6S"
TOLERANCE"20%"
VALUE"22UF"
PART_NUMBER"CH622KMEB02"
VOLTAGE"4V"
PACK_TYPE"C0402"
CDS_LIB"pure_quanta";
"B"
$PN"2"20;
"A"
$PN"1"19;
%"Q_CAP"
"1","(-3525,2075)","0","pure_quanta","I66";
;
LOCATION"C2217"
$SEC"1"
CDS_SEC"1"
MATERIAL"X6S"
TOLERANCE"20%"
VALUE"22UF"
PART_NUMBER"CH622KMEB02"
VOLTAGE"4V"
PACK_TYPE"C0402"
CDS_LIB"pure_quanta";
"B"
$PN"2"20;
"A"
$PN"1"19;
%"Q_CAP"
"1","(-3075,2075)","0","pure_quanta","I67";
;
LOCATION"C2223"
$SEC"1"
CDS_SEC"1"
MATERIAL"X6S"
TOLERANCE"20%"
VALUE"22UF"
PART_NUMBER"CH622KMEB02"
VOLTAGE"4V"
PACK_TYPE"C0402"
CDS_LIB"pure_quanta";
"B"
$PN"2"20;
"A"
$PN"1"19;
%"UNIVERSAL_GND"
"1","(-2625,1725)","0","pure_quanta_power","I68";
;
CDS_LIB"pure_quanta_power"
HDL_POWER"GND";
"A"20;
%"Q_CAP"
"1","(-2625,2075)","0","pure_quanta","I69";
;
LOCATION"C2229"
$SEC"1"
CDS_SEC"1"
MATERIAL"X6S"
TOLERANCE"20%"
VALUE"22UF"
PART_NUMBER"CH622KMEB02"
VOLTAGE"4V"
PACK_TYPE"C0402"
CDS_LIB"pure_quanta";
"B"
$PN"2"20;
"A"
$PN"1"19;
%"Q_CAP"
"1","(-9000,3675)","0","pure_quanta","I7";
;
LOCATION"C2165"
$SEC"1"
CDS_SEC"1"
MATERIAL"X6S"
TOLERANCE"20%"
VALUE"22UF"
PART_NUMBER"CH622KMEB02"
VOLTAGE"4V"
PACK_TYPE"C0402"
CDS_LIB"pure_quanta";
"B"
$PN"2"6;
"A"
$PN"1"5;
%"Q_CAP"
"1","(-3975,2875)","0","pure_quanta","I70";
;
LOCATION"C2210"
$SEC"1"
CDS_SEC"1"
MATERIAL"X6S"
TOLERANCE"20%"
VALUE"22UF"
PART_NUMBER"CH622KMEB02"
VOLTAGE"4V"
PACK_TYPE"C0402"
CDS_LIB"pure_quanta";
"B"
$PN"2"18;
"A"
$PN"1"17;
%"Q_CAP"
"1","(-3525,2875)","0","pure_quanta","I71";
;
LOCATION"C2216"
$SEC"1"
CDS_SEC"1"
MATERIAL"X6S"
TOLERANCE"20%"
VALUE"22UF"
PART_NUMBER"CH622KMEB02"
VOLTAGE"4V"
PACK_TYPE"C0402"
CDS_LIB"pure_quanta";
"B"
$PN"2"18;
"A"
$PN"1"17;
%"Q_CAP"
"1","(-3975,3675)","0","pure_quanta","I72";
;
LOCATION"C2209"
$SEC"1"
CDS_SEC"1"
MATERIAL"X6S"
TOLERANCE"20%"
VALUE"22UF"
PART_NUMBER"CH622KMEB02"
VOLTAGE"4V"
PACK_TYPE"C0402"
CDS_LIB"pure_quanta";
"B"
$PN"2"16;
"A"
$PN"1"15;
%"Q_CAP"
"1","(-3525,3675)","0","pure_quanta","I73";
;
LOCATION"C2215"
$SEC"1"
CDS_SEC"1"
MATERIAL"X6S"
TOLERANCE"20%"
VALUE"22UF"
PART_NUMBER"CH622KMEB02"
VOLTAGE"4V"
PACK_TYPE"C0402"
CDS_LIB"pure_quanta";
"B"
$PN"2"16;
"A"
$PN"1"15;
%"Q_CAP"
"1","(-3075,2875)","0","pure_quanta","I74";
;
LOCATION"C2222"
$SEC"1"
CDS_SEC"1"
MATERIAL"X6S"
TOLERANCE"20%"
VALUE"22UF"
PART_NUMBER"CH622KMEB02"
VOLTAGE"4V"
PACK_TYPE"C0402"
CDS_LIB"pure_quanta";
"B"
$PN"2"18;
"A"
$PN"1"17;
%"Q_CAP"
"1","(-2625,2875)","0","pure_quanta","I75";
;
LOCATION"C2228"
$SEC"1"
CDS_SEC"1"
MATERIAL"X6S"
TOLERANCE"20%"
VALUE"22UF"
PART_NUMBER"CH622KMEB02"
VOLTAGE"4V"
PACK_TYPE"C0402"
CDS_LIB"pure_quanta";
"B"
$PN"2"18;
"A"
$PN"1"17;
%"Q_CAP"
"1","(-2175,2875)","0","pure_quanta","I76";
;
LOCATION"C2234"
$SEC"1"
CDS_SEC"1"
MATERIAL"X6S"
TOLERANCE"20%"
VALUE"22UF"
PART_NUMBER"CH622KMEB02"
VOLTAGE"4V"
PACK_TYPE"C0402"
CDS_LIB"pure_quanta";
"B"
$PN"2"18;
"A"
$PN"1"17;
%"Q_CAP"
"1","(-3075,3675)","0","pure_quanta","I77";
;
LOCATION"C2221"
$SEC"1"
CDS_SEC"1"
MATERIAL"X6S"
TOLERANCE"20%"
VALUE"22UF"
PART_NUMBER"CH622KMEB02"
VOLTAGE"4V"
PACK_TYPE"C0402"
CDS_LIB"pure_quanta";
"B"
$PN"2"16;
"A"
$PN"1"15;
%"Q_CAP"
"1","(-2625,3675)","0","pure_quanta","I78";
;
LOCATION"C2227"
$SEC"1"
CDS_SEC"1"
MATERIAL"X6S"
TOLERANCE"20%"
VALUE"22UF"
PART_NUMBER"CH622KMEB02"
VOLTAGE"4V"
PACK_TYPE"C0402"
CDS_LIB"pure_quanta";
"B"
$PN"2"16;
"A"
$PN"1"15;
%"Q_CAP"
"1","(-2175,3675)","0","pure_quanta","I79";
;
LOCATION"C2233"
$SEC"1"
CDS_SEC"1"
MATERIAL"X6S"
TOLERANCE"20%"
VALUE"22UF"
PART_NUMBER"CH622KMEB02"
VOLTAGE"4V"
PACK_TYPE"C0402"
CDS_LIB"pure_quanta";
"B"
$PN"2"16;
"A"
$PN"1"15;
%"UNIVERSAL_POWER"
"1","(-9000,3950)","0","pure_quanta_power","I8";
;
HDL_POWER"PVDDCR_CPU0_P0"
CDS_LIB"pure_quanta_power";
"A"5;
%"Q_CAP"
"1","(-1725,2875)","0","pure_quanta","I80";
;
LOCATION"C2240"
$SEC"1"
CDS_SEC"1"
MATERIAL"X6S"
TOLERANCE"20%"
VALUE"22UF"
PART_NUMBER"CH622KMEB02"
VOLTAGE"4V"
PACK_TYPE"C0402"
CDS_LIB"pure_quanta";
"B"
$PN"2"18;
"A"
$PN"1"17;
%"Q_CAP"
"1","(-1275,2875)","0","pure_quanta","I81";
;
LOCATION"C2246"
$SEC"1"
CDS_SEC"1"
MATERIAL"X6S"
TOLERANCE"20%"
VALUE"22UF"
PART_NUMBER"CH622KMEB02"
VOLTAGE"4V"
PACK_TYPE"C0402"
CDS_LIB"pure_quanta";
"B"
$PN"2"18;
"A"
$PN"1"17;
%"Q_CAP"
"1","(-1725,3675)","0","pure_quanta","I82";
;
LOCATION"C2239"
$SEC"1"
CDS_SEC"1"
MATERIAL"X6S"
TOLERANCE"20%"
VALUE"22UF"
PART_NUMBER"CH622KMEB02"
VOLTAGE"4V"
PACK_TYPE"C0402"
CDS_LIB"pure_quanta";
"B"
$PN"2"16;
"A"
$PN"1"15;
%"Q_CAP"
"1","(-1275,3675)","0","pure_quanta","I83";
;
LOCATION"C2245"
$SEC"1"
CDS_SEC"1"
MATERIAL"X6S"
TOLERANCE"20%"
VALUE"22UF"
PART_NUMBER"CH622KMEB02"
VOLTAGE"4V"
PACK_TYPE"C0402"
CDS_LIB"pure_quanta";
"B"
$PN"2"16;
"A"
$PN"1"15;
%"Q_CAP"
"1","(-825,2875)","0","pure_quanta","I84";
;
LOCATION"C2251"
$SEC"1"
CDS_SEC"1"
MATERIAL"X6S"
TOLERANCE"20%"
VALUE"22UF"
PART_NUMBER"CH622KMEB02"
VOLTAGE"4V"
PACK_TYPE"C0402"
CDS_LIB"pure_quanta";
"B"
$PN"2"18;
"A"
$PN"1"17;
%"UNIVERSAL_GND"
"1","(-425,2500)","0","pure_quanta_power","I85";
;
CDS_LIB"pure_quanta_power"
HDL_POWER"GND";
"A"18;
%"Q_CAP"
"1","(-425,2875)","0","pure_quanta","I86";
;
LOCATION"C2256"
$SEC"1"
CDS_SEC"1"
MATERIAL"X6S"
TOLERANCE"20%"
VALUE"22UF"
PART_NUMBER"CH622KMEB02"
VOLTAGE"4V"
PACK_TYPE"C0402"
CDS_LIB"pure_quanta";
"B"
$PN"2"18;
"A"
$PN"1"17;
%"Q_CAP"
"1","(-825,3675)","0","pure_quanta","I87";
;
LOCATION"C2250"
$SEC"1"
CDS_SEC"1"
MATERIAL"X6S"
TOLERANCE"20%"
VALUE"22UF"
PART_NUMBER"CH622KMEB02"
VOLTAGE"4V"
PACK_TYPE"C0402"
CDS_LIB"pure_quanta";
"B"
$PN"2"16;
"A"
$PN"1"15;
%"UNIVERSAL_GND"
"1","(-425,3300)","0","pure_quanta_power","I88";
;
CDS_LIB"pure_quanta_power"
HDL_POWER"GND";
"A"16;
%"Q_CAP"
"1","(-425,3675)","0","pure_quanta","I89";
;
LOCATION"C2255"
$SEC"1"
CDS_SEC"1"
MATERIAL"X6S"
TOLERANCE"20%"
VALUE"22UF"
PART_NUMBER"CH622KMEB02"
VOLTAGE"4V"
PACK_TYPE"C0402"
CDS_LIB"pure_quanta";
"B"
$PN"2"16;
"A"
$PN"1"15;
%"Q_CAP"
"1","(-8550,3675)","0","pure_quanta","I9";
;
LOCATION"C2169"
$SEC"1"
CDS_SEC"1"
MATERIAL"X6S"
TOLERANCE"20%"
VALUE"22UF"
PART_NUMBER"CH622KMEB02"
VOLTAGE"4V"
PACK_TYPE"C0402"
CDS_LIB"pure_quanta";
"B"
$PN"2"6;
"A"
$PN"1"5;
%"UNIVERSAL_GND"
"1","(-425,4100)","0","pure_quanta_power","I90";
;
CDS_LIB"pure_quanta_power"
HDL_POWER"GND";
"A"14;
%"Q_CAP"
"1","(-3975,4475)","0","pure_quanta","I91";
;
LOCATION"C2208"
$SEC"1"
CDS_SEC"1"
MATERIAL"X6S"
TOLERANCE"20%"
VALUE"22UF"
PART_NUMBER"CH622KMEB02"
VOLTAGE"4V"
PACK_TYPE"C0402"
CDS_LIB"pure_quanta";
"B"
$PN"2"14;
"A"
$PN"1"13;
%"Q_CAP"
"1","(-3525,4475)","0","pure_quanta","I92";
;
LOCATION"C2214"
$SEC"1"
CDS_SEC"1"
MATERIAL"X6S"
TOLERANCE"20%"
VALUE"22UF"
PART_NUMBER"CH622KMEB02"
VOLTAGE"4V"
PACK_TYPE"C0402"
CDS_LIB"pure_quanta";
"B"
$PN"2"14;
"A"
$PN"1"13;
%"Q_CAP"
"1","(-3975,5250)","0","pure_quanta","I93";
;
LOCATION"C2207"
$SEC"1"
CDS_SEC"1"
MATERIAL"X6S"
TOLERANCE"20%"
VALUE"22UF"
PART_NUMBER"CH622KMEB02"
VOLTAGE"4V"
PACK_TYPE"C0402"
CDS_LIB"pure_quanta";
"B"
$PN"2"12;
"A"
$PN"1"11;
%"Q_CAP"
"1","(-3525,5250)","0","pure_quanta","I94";
;
LOCATION"C2213"
$SEC"1"
CDS_SEC"1"
MATERIAL"X6S"
TOLERANCE"20%"
VALUE"22UF"
PART_NUMBER"CH622KMEB02"
VOLTAGE"4V"
PACK_TYPE"C0402"
CDS_LIB"pure_quanta";
"B"
$PN"2"12;
"A"
$PN"1"11;
%"Q_CAP"
"1","(-3075,4475)","0","pure_quanta","I95";
;
LOCATION"C2220"
$SEC"1"
CDS_SEC"1"
MATERIAL"X6S"
TOLERANCE"20%"
VALUE"22UF"
PART_NUMBER"CH622KMEB02"
VOLTAGE"4V"
PACK_TYPE"C0402"
CDS_LIB"pure_quanta";
"B"
$PN"2"14;
"A"
$PN"1"13;
%"Q_CAP"
"1","(-2625,4475)","0","pure_quanta","I96";
;
LOCATION"C2226"
$SEC"1"
CDS_SEC"1"
MATERIAL"X6S"
TOLERANCE"20%"
VALUE"22UF"
PART_NUMBER"CH622KMEB02"
VOLTAGE"4V"
PACK_TYPE"C0402"
CDS_LIB"pure_quanta";
"B"
$PN"2"14;
"A"
$PN"1"13;
%"Q_CAP"
"1","(-2175,4475)","0","pure_quanta","I97";
;
LOCATION"C2232"
$SEC"1"
CDS_SEC"1"
MATERIAL"X6S"
TOLERANCE"20%"
VALUE"22UF"
PART_NUMBER"CH622KMEB02"
VOLTAGE"4V"
PACK_TYPE"C0402"
CDS_LIB"pure_quanta";
"B"
$PN"2"14;
"A"
$PN"1"13;
%"Q_CAP"
"1","(-3075,5250)","0","pure_quanta","I98";
;
LOCATION"C2219"
$SEC"1"
CDS_SEC"1"
MATERIAL"X6S"
TOLERANCE"20%"
VALUE"22UF"
PART_NUMBER"CH622KMEB02"
VOLTAGE"4V"
PACK_TYPE"C0402"
CDS_LIB"pure_quanta";
"B"
$PN"2"12;
"A"
$PN"1"11;
%"Q_CAP"
"1","(-2625,5250)","0","pure_quanta","I99";
;
LOCATION"C2225"
$SEC"1"
CDS_SEC"1"
MATERIAL"X6S"
TOLERANCE"20%"
VALUE"22UF"
PART_NUMBER"CH622KMEB02"
VOLTAGE"4V"
PACK_TYPE"C0402"
CDS_LIB"pure_quanta";
"B"
$PN"2"12;
"A"
$PN"1"11;
END.
